(kicad_pcb
	(version 20260206)
	(generator "pcbnew")
	(generator_version "10.0")
	(general
		(thickness 1.6)
		(legacy_teardrops no)
	)
	(paper "A4")
	(title_block
		(title "timecard-production-celestica-r4006 — R4006-B0001-02_R01.brd")
		(comment 1 "Time Appliance Project (Time Card) / footprints 990-994 of 1113")
	)
	(layers
		(0 "F.Cu" signal "TOP")
		(4 "In1.Cu" signal "L02_GND1")
		(6 "In2.Cu" signal "L03_SIG1")
		(8 "In3.Cu" signal "L04_GND2")
		(10 "In4.Cu" signal "L05_VCC1")
		(12 "In5.Cu" signal "L06_VCC2")
		(14 "In6.Cu" signal "L07_GND3")
		(16 "In7.Cu" signal "L08_SIG2")
		(18 "In8.Cu" signal "L09_GND4")
		(2 "B.Cu" signal "BOTTOM")
		(9 "F.Adhes" user "F.Adhesive")
		(11 "B.Adhes" user "B.Adhesive")
		(13 "F.Paste" user "Package Geometry/Pastemask Top")
		(15 "B.Paste" user "Package Geometry/Pastemask Bottom")
		(5 "F.SilkS" user "Ref Des/Silkscreen Top")
		(7 "B.SilkS" user "Ref Des/Silkscreen Bottom")
		(1 "F.Mask" user "Board Geometry/Soldermask Top")
		(3 "B.Mask" user "Board Geometry/Soldermask Bottom")
		(17 "Dwgs.User" user "User.Drawings")
		(19 "Cmts.User" user "User.Comments")
		(21 "Eco1.User" user "User.Eco1")
		(23 "Eco2.User" user "User.Eco2")
		(25 "Edge.Cuts" user "Board Geometry/Outline")
		(27 "Margin" user)
		(31 "F.CrtYd" user "Package Geometry/Place Bound Top")
		(29 "B.CrtYd" user "Package Geometry/Place Bound Bottom")
		(35 "F.Fab" user "Ref Des/Assembly Top")
		(33 "B.Fab" user "Ref Des/Assembly Bottom")
	)
	(footprint ""
		(layer "B.Cu")
		(at 88.519 -83.312 180)
		(property "Reference" "R202"
			(at -0.254 5.54863 0)
			(unlocked yes)
			(layer "B.SilkS")
			(effects
				(font
					(size 0.7874 0.5842)
					(thickness 0.1524)
				)
				(justify mirror)
			)
		)
		(property "Value" "VAL*"
			(at -0.02032 2.13233 180)
			(unlocked yes)
			(layer "B.Fab")
			(hide yes)
			(effects
				(font
					(size 0.7874 0.5842)
					(thickness 0.1524)
				)
				(justify mirror)
			)
		)
		(property "Tolerance" "TOL*"
			(at -0.044704 3.05435 180)
			(unlocked yes)
			(layer "Cmts.User")
			(hide yes)
			(effects
				(font
					(size 0.7874 0.5842)
					(thickness 0.1524)
				)
				(justify mirror)
			)
		)
		(property "User Part Number" "PARTNUM*"
			(at -0.02032 4.024884 180)
			(unlocked yes)
			(layer "Cmts.User")
			(hide yes)
			(effects
				(font
					(size 0.7874 0.5842)
					(thickness 0.1524)
				)
				(justify mirror)
			)
		)
		(property "Device Type" "RESISTOR-G155-14701-01,4.7KOHMA"
			(at -0.008382 1.210564 180)
			(unlocked yes)
			(layer "B.Fab")
			(hide yes)
			(effects
				(font
					(size 0.7874 0.5842)
					(thickness 0.1524)
				)
				(justify mirror)
			)
		)
		(duplicate_pad_numbers_are_jumpers no)
		(fp_line
			(start 1.143 0.5588)
			(end -1.143 0.5588)
			(stroke
				(width 0.1)
				(type default)
			)
			(layer "B.SilkS")
		)
		(fp_line
			(start 1.143 -0.5588)
			(end 1.143 0.5588)
			(stroke
				(width 0.1)
				(type default)
			)
			(layer "B.SilkS")
		)
		(fp_line
			(start -1.143 0.5588)
			(end -1.143 -0.5588)
			(stroke
				(width 0.1)
				(type default)
			)
			(layer "B.SilkS")
		)
		(fp_line
			(start -1.143 -0.5588)
			(end 1.143 -0.5588)
			(stroke
				(width 0.1)
				(type default)
			)
			(layer "B.SilkS")
		)
		(fp_rect
			(start 1.143 -0.5588)
			(end -1.143 0.5588)
			(stroke
				(width 0)
				(type default)
			)
			(fill no)
			(layer "B.CrtYd")
		)
		(fp_line
			(start 0.508 0.3048)
			(end -0.508 0.3048)
			(stroke
				(width 0.1)
				(type default)
			)
			(layer "B.Fab")
		)
		(fp_line
			(start 0.508 -0.3048)
			(end 0.508 0.3048)
			(stroke
				(width 0.1)
				(type default)
			)
			(layer "B.Fab")
		)
		(fp_line
			(start -0.508 0.3048)
			(end -0.508 -0.3048)
			(stroke
				(width 0.1)
				(type default)
			)
			(layer "B.Fab")
		)
		(fp_line
			(start -0.508 -0.3048)
			(end 0.508 -0.3048)
			(stroke
				(width 0.1)
				(type default)
			)
			(layer "B.Fab")
		)
		(pad "1" smd rect
			(at 0.5334 0)
			(size 0.7112 0.6096)
			(layers "B.Cu" "B.Mask" "B.Paste")
			(net "UNNAMED_127_MT25QL128ABA1ESES_2")
		)
		(pad "2" smd rect
			(at -0.5334 0)
			(size 0.7112 0.6096)
			(layers "B.Cu" "B.Mask" "B.Paste")
			(net "XP3R3V_FPGA")
		)
		(zone
			(layer "B.Cu")
			(hatch none 0.5)
			(connect_pads
				(clearance 0)
			)
			(min_thickness 0.25)
			(keepout
				(tracks allowed)
				(vias not_allowed)
				(pads allowed)
				(copperpour not_allowed)
				(footprints allowed)
			)
			(placement
				(enabled no)
				(sheetname "")
			)
			(fill
				(thermal_gap 0.5)
				(thermal_bridge_width 0.5)
				(island_removal_mode 0)
			)
			(polygon
				(pts
					(xy 88.4428 -83.0072) (xy 88.5952 -83.0072) (xy 88.5952 -83.6168) (xy 88.4428 -83.6168)
				)
			)
		)
	)
	(footprint ""
		(layer "B.Cu")
		(at 139.6492 -83.5152)
		(property "Reference" "C299"
			(at 0.4318 -6.61543 0)
			(unlocked yes)
			(layer "B.SilkS")
			(effects
				(font
					(size 0.7874 0.5842)
					(thickness 0.1524)
				)
				(justify mirror)
			)
		)
		(property "Value" "VAL*"
			(at -0.0762 3.134106 0)
			(unlocked yes)
			(layer "B.Fab")
			(hide yes)
			(effects
				(font
					(size 0.7874 0.5842)
					(thickness 0.1524)
				)
				(justify mirror)
			)
		)
		(property "Device Type" "CAPACITOR-G107-0F106-EM,10UF,2A"
			(at -0.0508 2.194306 0)
			(unlocked yes)
			(layer "B.Fab")
			(hide yes)
			(effects
				(font
					(size 0.7874 0.5842)
					(thickness 0.1524)
				)
				(justify mirror)
			)
		)
		(property "User Part Number" "PARTNUM*"
			(at -0.1016 5.013706 0)
			(unlocked yes)
			(layer "Cmts.User")
			(hide yes)
			(effects
				(font
					(size 0.7874 0.5842)
					(thickness 0.1524)
				)
				(justify mirror)
			)
		)
		(property "Tolerance" "TOL*"
			(at -0.0762 4.048506 0)
			(unlocked yes)
			(layer "Cmts.User")
			(hide yes)
			(effects
				(font
					(size 0.7874 0.5842)
					(thickness 0.1524)
				)
				(justify mirror)
			)
		)
		(duplicate_pad_numbers_are_jumpers no)
		(fp_line
			(start -1.5748 -0.9398)
			(end 1.5748 -0.9398)
			(stroke
				(width 0.1)
				(type default)
			)
			(layer "B.SilkS")
		)
		(fp_line
			(start -1.5748 0.9398)
			(end -1.5748 -0.9398)
			(stroke
				(width 0.1)
				(type default)
			)
			(layer "B.SilkS")
		)
		(fp_line
			(start 1.5748 -0.9398)
			(end 1.5748 0.9398)
			(stroke
				(width 0.1)
				(type default)
			)
			(layer "B.SilkS")
		)
		(fp_line
			(start 1.5748 0.9398)
			(end -1.5748 0.9398)
			(stroke
				(width 0.1)
				(type default)
			)
			(layer "B.SilkS")
		)
		(fp_rect
			(start 1.5748 -0.9398)
			(end -1.5748 0.9398)
			(stroke
				(width 0)
				(type default)
			)
			(fill no)
			(layer "B.CrtYd")
		)
		(fp_line
			(start -1.016 -0.635)
			(end 1.016 -0.635)
			(stroke
				(width 0.1)
				(type default)
			)
			(layer "B.Fab")
		)
		(fp_line
			(start -1.016 0.635)
			(end -1.016 -0.635)
			(stroke
				(width 0.1)
				(type default)
			)
			(layer "B.Fab")
		)
		(fp_line
			(start 1.016 -0.635)
			(end 1.016 0.635)
			(stroke
				(width 0.1)
				(type default)
			)
			(layer "B.Fab")
		)
		(fp_line
			(start 1.016 0.635)
			(end -1.016 0.635)
			(stroke
				(width 0.1)
				(type default)
			)
			(layer "B.Fab")
		)
		(pad "1" smd rect
			(at 0.8382 0 180)
			(size 0.9652 1.3716)
			(layers "B.Cu" "B.Mask" "B.Paste")
			(net "XP12R0V_IN")
		)
		(pad "2" smd rect
			(at -0.8382 0 180)
			(size 0.9652 1.3716)
			(layers "B.Cu" "B.Mask" "B.Paste")
			(net "SG")
		)
		(zone
			(layer "B.Cu")
			(hatch none 0.5)
			(connect_pads
				(clearance 0)
			)
			(min_thickness 0.25)
			(keepout
				(tracks not_allowed)
				(vias allowed)
				(pads allowed)
				(copperpour not_allowed)
				(footprints allowed)
			)
			(placement
				(enabled no)
				(sheetname "")
			)
			(fill
				(thermal_gap 0.5)
				(thermal_bridge_width 0.5)
				(island_removal_mode 0)
			)
			(polygon
				(pts
					(xy 139.8778 -84.1502) (xy 139.4206 -84.1502) (xy 139.4206 -82.8802) (xy 139.8778 -82.8802)
				)
			)
		)
		(zone
			(layer "B.Cu")
			(hatch none 0.5)
			(connect_pads
				(clearance 0)
			)
			(min_thickness 0.25)
			(keepout
				(tracks allowed)
				(vias not_allowed)
				(pads allowed)
				(copperpour not_allowed)
				(footprints allowed)
			)
			(placement
				(enabled no)
				(sheetname "")
			)
			(fill
				(thermal_gap 0.5)
				(thermal_bridge_width 0.5)
				(island_removal_mode 0)
			)
			(polygon
				(pts
					(xy 139.8778 -84.1502) (xy 139.4206 -84.1502) (xy 139.4206 -82.8802) (xy 139.8778 -82.8802)
				)
			)
		)
	)
	(footprint ""
		(layer "B.Cu")
		(at 147.066 -107.696 90)
		(property "Reference" "R261"
			(at 0 1.99263 270)
			(unlocked yes)
			(layer "B.SilkS")
			(effects
				(font
					(size 0.7874 0.5842)
					(thickness 0.1524)
				)
				(justify mirror)
			)
		)
		(property "Value" "VAL*"
			(at -0.02032 2.13233 90)
			(unlocked yes)
			(layer "B.Fab")
			(hide yes)
			(effects
				(font
					(size 0.7874 0.5842)
					(thickness 0.1524)
				)
				(justify mirror)
			)
		)
		(property "Device Type" "RESISTOR-G155-13300-01,330OHM,A"
			(at -0.008382 1.210564 90)
			(unlocked yes)
			(layer "B.Fab")
			(hide yes)
			(effects
				(font
					(size 0.7874 0.5842)
					(thickness 0.1524)
				)
				(justify mirror)
			)
		)
		(property "User Part Number" "PARTNUM*"
			(at -0.02032 4.024884 90)
			(unlocked yes)
			(layer "Cmts.User")
			(hide yes)
			(effects
				(font
					(size 0.7874 0.5842)
					(thickness 0.1524)
				)
				(justify mirror)
			)
		)
		(property "Tolerance" "TOL*"
			(at -0.044704 3.05435 90)
			(unlocked yes)
			(layer "Cmts.User")
			(hide yes)
			(effects
				(font
					(size 0.7874 0.5842)
					(thickness 0.1524)
				)
				(justify mirror)
			)
		)
		(duplicate_pad_numbers_are_jumpers no)
		(fp_line
			(start 1.143 -0.5588)
			(end 1.143 0.5588)
			(stroke
				(width 0.1)
				(type default)
			)
			(layer "B.SilkS")
		)
		(fp_line
			(start -1.143 -0.5588)
			(end 1.143 -0.5588)
			(stroke
				(width 0.1)
				(type default)
			)
			(layer "B.SilkS")
		)
		(fp_line
			(start 1.143 0.5588)
			(end -1.143 0.5588)
			(stroke
				(width 0.1)
				(type default)
			)
			(layer "B.SilkS")
		)
		(fp_line
			(start -1.143 0.5588)
			(end -1.143 -0.5588)
			(stroke
				(width 0.1)
				(type default)
			)
			(layer "B.SilkS")
		)
		(fp_rect
			(start -1.143 -0.5588)
			(end 1.143 0.5588)
			(stroke
				(width 0)
				(type default)
			)
			(fill no)
			(layer "B.CrtYd")
		)
		(fp_line
			(start 0.508 -0.3048)
			(end 0.508 0.3048)
			(stroke
				(width 0.1)
				(type default)
			)
			(layer "B.Fab")
		)
		(fp_line
			(start -0.508 -0.3048)
			(end 0.508 -0.3048)
			(stroke
				(width 0.1)
				(type default)
			)
			(layer "B.Fab")
		)
		(fp_line
			(start 0.508 0.3048)
			(end -0.508 0.3048)
			(stroke
				(width 0.1)
				(type default)
			)
			(layer "B.Fab")
		)
		(fp_line
			(start -0.508 0.3048)
			(end -0.508 -0.3048)
			(stroke
				(width 0.1)
				(type default)
			)
			(layer "B.Fab")
		)
		(pad "1" smd rect
			(at 0.5334 0 270)
			(size 0.7112 0.6096)
			(layers "B.Cu" "B.Mask" "B.Paste")
			(net "UNNAMED_14_OPTICAL_I137_A")
		)
		(pad "2" smd rect
			(at -0.5334 0 270)
			(size 0.7112 0.6096)
			(layers "B.Cu" "B.Mask" "B.Paste")
			(net "XP3R3V_FPGA")
		)
		(zone
			(layer "B.Cu")
			(hatch none 0.5)
			(connect_pads
				(clearance 0)
			)
			(min_thickness 0.25)
			(keepout
				(tracks allowed)
				(vias not_allowed)
				(pads allowed)
				(copperpour not_allowed)
				(footprints allowed)
			)
			(placement
				(enabled no)
				(sheetname "")
			)
			(fill
				(thermal_gap 0.5)
				(thermal_bridge_width 0.5)
				(island_removal_mode 0)
			)
			(polygon
				(pts
					(xy 146.7612 -107.6198) (xy 147.3708 -107.6198) (xy 147.3708 -107.7722) (xy 146.7612 -107.7722)
				)
			)
		)
	)
	(footprint ""
		(layer "B.Cu")
		(at 100.347018 -46.823122 180)
		(property "Reference" "C203"
			(at 2.303018 -0.118872 0)
			(unlocked yes)
			(layer "B.SilkS")
			(effects
				(font
					(size 0.635 0.4064)
					(thickness 0.1524)
				)
				(justify mirror)
			)
		)
		(property "Value" "VAL*"
			(at 0 3.718306 180)
			(unlocked yes)
			(layer "B.Fab")
			(hide yes)
			(effects
				(font
					(size 0.7874 0.5842)
					(thickness 0.127)
				)
				(justify mirror)
			)
		)
		(property "Device Type" "CAPACITOR-G105-0B104-CK,0.1UF,A"
			(at 0 1.432306 180)
			(unlocked yes)
			(layer "B.Fab")
			(hide yes)
			(effects
				(font
					(size 0.7874 0.5842)
					(thickness 0.127)
				)
				(justify mirror)
			)
		)
		(property "User Part Number" "PARTNUM*"
			(at 0 2.575306 180)
			(unlocked yes)
			(layer "Cmts.User")
			(hide yes)
			(effects
				(font
					(size 0.7874 0.5842)
					(thickness 0.127)
				)
				(justify mirror)
			)
		)
		(property "Tolerance" "TOL*"
			(at 0 4.861306 180)
			(unlocked yes)
			(layer "Cmts.User")
			(hide yes)
			(effects
				(font
					(size 0.7874 0.5842)
					(thickness 0.127)
				)
				(justify mirror)
			)
		)
		(duplicate_pad_numbers_are_jumpers no)
		(fp_line
			(start 0.970026 0.4699)
			(end 0.970026 -0.4699)
			(stroke
				(width 0.1)
				(type default)
			)
			(layer "B.SilkS")
		)
		(fp_line
			(start 0.970026 -0.4699)
			(end -0.970026 -0.4699)
			(stroke
				(width 0.1)
				(type default)
			)
			(layer "B.SilkS")
		)
		(fp_line
			(start -0.970026 0.4699)
			(end 0.970026 0.4699)
			(stroke
				(width 0.1)
				(type default)
			)
			(layer "B.SilkS")
		)
		(fp_line
			(start -0.970026 -0.4699)
			(end -0.970026 0.4699)
			(stroke
				(width 0.1)
				(type default)
			)
			(layer "B.SilkS")
		)
		(fp_poly
			(pts
				(xy 0.970026 0.4699) (xy -0.970026 0.4699) (xy -0.970026 -0.4699) (xy 0.970026 -0.4699)
			)
			(stroke
				(width 0)
				(type default)
			)
			(fill no)
			(layer "B.CrtYd")
		)
		(fp_line
			(start 0.508 0.3048)
			(end 0.508 -0.3048)
			(stroke
				(width 0.1)
				(type default)
			)
			(layer "B.Fab")
		)
		(fp_line
			(start 0.508 -0.3048)
			(end -0.508 -0.3048)
			(stroke
				(width 0.1)
				(type default)
			)
			(layer "B.Fab")
		)
		(fp_line
			(start -0.508 0.3048)
			(end 0.508 0.3048)
			(stroke
				(width 0.1)
				(type default)
			)
			(layer "B.Fab")
		)
		(fp_line
			(start -0.508 -0.3048)
			(end -0.508 0.3048)
			(stroke
				(width 0.1)
				(type default)
			)
			(layer "B.Fab")
		)
		(pad "1" smd circle
			(at 0.500126 0)
			(size 0.635 0.635)
			(layers "B.Cu" "B.Mask" "B.Paste")
			(net "XP3R3V_FPGA")
		)
		(pad "2" smd circle
			(at -0.500126 0)
			(size 0.635 0.635)
			(layers "B.Cu" "B.Mask" "B.Paste")
			(net "SG")
		)
	)
	(footprint ""
		(layer "B.Cu")
		(at 111.847122 -34.32302 -90)
		(property "Reference" "C108"
			(at 2.06502 -0.008128 270)
			(unlocked yes)
			(layer "B.SilkS")
			(effects
				(font
					(size 0.635 0.4064)
					(thickness 0.1524)
				)
				(justify mirror)
			)
		)
		(property "Value" "VAL*"
			(at 0 3.718306 270)
			(unlocked yes)
			(layer "B.Fab")
			(hide yes)
			(effects
				(font
					(size 0.7874 0.5842)
					(thickness 0.127)
				)
				(justify mirror)
			)
		)
		(property "Tolerance" "TOL*"
			(at 0 4.861306 270)
			(unlocked yes)
			(layer "Cmts.User")
			(hide yes)
			(effects
				(font
					(size 0.7874 0.5842)
					(thickness 0.127)
				)
				(justify mirror)
			)
		)
		(property "User Part Number" "PARTNUM*"
			(at 0 2.575306 270)
			(unlocked yes)
			(layer "Cmts.User")
			(hide yes)
			(effects
				(font
					(size 0.7874 0.5842)
					(thickness 0.127)
				)
				(justify mirror)
			)
		)
		(property "Device Type" "CAPACITOR-G105-0B104-CK,0.1UF,A"
			(at 0 1.432306 270)
			(unlocked yes)
			(layer "B.Fab")
			(hide yes)
			(effects
				(font
					(size 0.7874 0.5842)
					(thickness 0.127)
				)
				(justify mirror)
			)
		)
		(duplicate_pad_numbers_are_jumpers no)
		(fp_line
			(start -0.970026 0.4699)
			(end 0.970026 0.4699)
			(stroke
				(width 0.1)
				(type default)
			)
			(layer "B.SilkS")
		)
		(fp_line
			(start 0.970026 0.4699)
			(end 0.970026 -0.4699)
			(stroke
				(width 0.1)
				(type default)
			)
			(layer "B.SilkS")
		)
		(fp_line
			(start -0.970026 -0.4699)
			(end -0.970026 0.4699)
			(stroke
				(width 0.1)
				(type default)
			)
			(layer "B.SilkS")
		)
		(fp_line
			(start 0.970026 -0.4699)
			(end -0.970026 -0.4699)
			(stroke
				(width 0.1)
				(type default)
			)
			(layer "B.SilkS")
		)
		(fp_poly
			(pts
				(xy 0.970026 0.4699) (xy -0.970026 0.4699) (xy -0.970026 -0.4699) (xy 0.970026 -0.4699)
			)
			(stroke
				(width 0)
				(type default)
			)
			(fill no)
			(layer "B.CrtYd")
		)
		(fp_line
			(start -0.508 0.3048)
			(end 0.508 0.3048)
			(stroke
				(width 0.1)
				(type default)
			)
			(layer "B.Fab")
		)
		(fp_line
			(start 0.508 0.3048)
			(end 0.508 -0.3048)
			(stroke
				(width 0.1)
				(type default)
			)
			(layer "B.Fab")
		)
		(fp_line
			(start -0.508 -0.3048)
			(end -0.508 0.3048)
			(stroke
				(width 0.1)
				(type default)
			)
			(layer "B.Fab")
		)
		(fp_line
			(start 0.508 -0.3048)
			(end -0.508 -0.3048)
			(stroke
				(width 0.1)
				(type default)
			)
			(layer "B.Fab")
		)
		(pad "1" smd circle
			(at 0.500126 0 90)
			(size 0.635 0.635)
			(layers "B.Cu" "B.Mask" "B.Paste")
			(net "XP2R5V_FPGA")
		)
		(pad "2" smd circle
			(at -0.500126 0 90)
			(size 0.635 0.635)
			(layers "B.Cu" "B.Mask" "B.Paste")
			(net "SG")
		)
	)
)
